(kicad_pcb
	(version 20260206)
	(generator "pcbnew")
	(generator_version "10.0")
	(general
		(thickness 1.6)
		(legacy_teardrops no)
	)
	(paper "A4")
	(title_block
		(title "Bryce Canyon_R.DPB_16317-1_OCP.brd")
		(comment 1 "Bryce Canyon / footprints 1712-1719 of 2099")
	)
	(layers
		(0 "F.Cu" signal "TOP")
		(4 "In1.Cu" signal "L2GND")
		(6 "In2.Cu" signal "L3")
		(8 "In3.Cu" signal "L4VCC")
		(10 "In4.Cu" signal "L5VCC")
		(12 "In5.Cu" signal "L6")
		(14 "In6.Cu" signal "L7GND")
		(2 "B.Cu" signal "BOTTOM")
		(9 "F.Adhes" user "F.Adhesive")
		(11 "B.Adhes" user "B.Adhesive")
		(13 "F.Paste" user "Package Geometry/Pastemask Top")
		(15 "B.Paste" user "Package Geometry/Pastemask Bottom")
		(5 "F.SilkS" user "Ref Des/Silkscreen Top")
		(7 "B.SilkS" user "Ref Des/Silkscreen Bottom")
		(1 "F.Mask" user "Board Geometry/Soldermask Top")
		(3 "B.Mask" user "Board Geometry/Soldermask Bottom")
		(17 "Dwgs.User" user "User.Drawings")
		(19 "Cmts.User" user "User.Comments")
		(21 "Eco1.User" user "User.Eco1")
		(23 "Eco2.User" user "User.Eco2")
		(25 "Edge.Cuts" user "Board Geometry/Outline")
		(27 "Margin" user)
		(31 "F.CrtYd" user "Package Geometry/Place Bound Top")
		(29 "B.CrtYd" user "Package Geometry/Place Bound Bottom")
		(35 "F.Fab" user "Ref Des/Assembly Top")
		(33 "B.Fab" user "Ref Des/Assembly Bottom")
	)
	(footprint ""
		(layer "F.Cu")
		(at 178.0032 -33.782 -90)
		(property "Reference" "C407"
			(at 0 0 270)
			(layer "F.SilkS")
			(hide yes)
			(effects
				(font
					(size 1.27 1.27)
				)
			)
		)
		(property "Value" "SC1U16V3KX-5GP"
			(at 0 -2.8194 270)
			(unlocked yes)
			(layer "F.Fab")
			(hide yes)
			(effects
				(font
					(size 1.016 1.016)
					(thickness 0.1524)
				)
			)
		)
		(property "Device Type" "C603H36"
			(at 0 -4.3434 270)
			(unlocked yes)
			(layer "F.Fab")
			(hide yes)
			(effects
				(font
					(size 1.016 1.016)
					(thickness 0.1524)
				)
			)
		)
		(duplicate_pad_numbers_are_jumpers no)
		(fp_line
			(start 0.508 0)
			(end -0.508 0)
			(stroke
				(width 0.2032)
				(type default)
			)
			(layer "F.SilkS")
		)
		(fp_rect
			(start -0.5842 1.3335)
			(end 0.5842 -1.3335)
			(stroke
				(width 0)
				(type default)
			)
			(fill no)
			(layer "F.CrtYd")
		)
		(fp_rect
			(start -0.5842 1.3335)
			(end 0.5842 -1.3335)
			(stroke
				(width 0)
				(type default)
			)
			(fill no)
			(layer "F.Fab")
		)
		(pad "1" smd custom
			(at 0 -0.762 270)
			(size 0.2159 0.2159)
			(layers "F.Cu" "F.Mask" "F.Paste")
			(net "P5V_HDD29")
			(options
				(clearance outline)
				(anchor circle)
			)
			(primitives
				(gr_poly
					(pts
						(arc
							(start -0.3302 -0.4318)
							(mid -0.402042 -0.402042)
							(end -0.4318 -0.3302)
						)
						(arc
							(start -0.4318 0.3302)
							(mid -0.402042 0.402042)
							(end -0.3302 0.4318)
						)
						(arc
							(start 0.3302 0.4318)
							(mid 0.402042 0.402042)
							(end 0.4318 0.3302)
						)
						(arc
							(start 0.4318 -0.3302)
							(mid 0.402042 -0.402042)
							(end 0.3302 -0.4318)
						)
					)
					(width 0)
					(fill yes)
				)
			)
		)
		(pad "2" smd custom
			(at 0 0.762 270)
			(size 0.2159 0.2159)
			(layers "F.Cu" "F.Mask" "F.Paste")
			(net "GND")
			(options
				(clearance outline)
				(anchor circle)
			)
			(primitives
				(gr_poly
					(pts
						(arc
							(start -0.3302 -0.4318)
							(mid -0.402042 -0.402042)
							(end -0.4318 -0.3302)
						)
						(arc
							(start -0.4318 0.3302)
							(mid -0.402042 0.402042)
							(end -0.3302 0.4318)
						)
						(arc
							(start 0.3302 0.4318)
							(mid 0.402042 0.402042)
							(end 0.4318 0.3302)
						)
						(arc
							(start 0.4318 -0.3302)
							(mid 0.402042 -0.402042)
							(end 0.3302 -0.4318)
						)
					)
					(width 0)
					(fill yes)
				)
			)
		)
	)
	(footprint ""
		(layer "F.Cu")
		(at 144.653 -246.634)
		(property "Reference" "R235"
			(at 0 0 0)
			(layer "F.SilkS")
			(hide yes)
			(effects
				(font
					(size 1.27 1.27)
				)
			)
		)
		(property "Value" "0R2J-2-GP"
			(at 0.064008 -3.993896 0)
			(unlocked yes)
			(layer "F.Fab")
			(hide yes)
			(effects
				(font
					(size 1.016 1.016)
					(thickness 0.1524)
				)
			)
		)
		(property "Device Type" "R402H16"
			(at 0.064008 -5.517896 0)
			(unlocked yes)
			(layer "F.Fab")
			(hide yes)
			(effects
				(font
					(size 1.016 1.016)
					(thickness 0.1524)
				)
			)
		)
		(duplicate_pad_numbers_are_jumpers no)
		(fp_line
			(start -0.508 -0.9398)
			(end -0.508 0.9398)
			(stroke
				(width 0.1524)
				(type default)
			)
			(layer "F.SilkS")
		)
		(fp_line
			(start 0.508 -0.9398)
			(end -0.508 -0.9398)
			(stroke
				(width 0.1524)
				(type default)
			)
			(layer "F.SilkS")
		)
		(fp_rect
			(start -0.508 0.9398)
			(end 0.508 -0.9398)
			(stroke
				(width 0)
				(type default)
			)
			(fill no)
			(layer "F.CrtYd")
		)
		(fp_rect
			(start -0.508 0.9398)
			(end 0.508 -0.9398)
			(stroke
				(width 0)
				(type default)
			)
			(fill no)
			(layer "F.Fab")
		)
		(pad "1" smd custom
			(at 0 -0.4445)
			(size 0.1397 0.1397)
			(layers "F.Cu" "F.Mask" "F.Paste")
			(net "SW_HDD_G4")
			(options
				(clearance outline)
				(anchor circle)
			)
			(primitives
				(gr_poly
					(pts
						(arc
							(start -0.1778 -0.2794)
							(mid -0.249642 -0.249642)
							(end -0.2794 -0.1778)
						)
						(arc
							(start -0.2794 0.1778)
							(mid -0.249642 0.249642)
							(end -0.1778 0.2794)
						)
						(arc
							(start 0.1778 0.2794)
							(mid 0.249642 0.249642)
							(end 0.2794 0.1778)
						)
						(arc
							(start 0.2794 -0.1778)
							(mid 0.249642 -0.249642)
							(end 0.1778 -0.2794)
						)
					)
					(width 0)
					(fill yes)
				)
			)
		)
		(pad "2" smd custom
			(at 0 0.4445)
			(size 0.1397 0.1397)
			(layers "F.Cu" "F.Mask" "F.Paste")
			(net "SW_HDD_R4")
			(options
				(clearance outline)
				(anchor circle)
			)
			(primitives
				(gr_poly
					(pts
						(arc
							(start -0.1778 -0.2794)
							(mid -0.249642 -0.249642)
							(end -0.2794 -0.1778)
						)
						(arc
							(start -0.2794 0.1778)
							(mid -0.249642 0.249642)
							(end -0.1778 0.2794)
						)
						(arc
							(start 0.1778 0.2794)
							(mid 0.249642 0.249642)
							(end 0.2794 0.1778)
						)
						(arc
							(start 0.2794 -0.1778)
							(mid 0.249642 -0.249642)
							(end 0.1778 -0.2794)
						)
					)
					(width 0)
					(fill yes)
				)
			)
		)
	)
	(footprint ""
		(layer "F.Cu")
		(at 174.625 -132.588 180)
		(property "Reference" "D17"
			(at 0 0 180)
			(layer "F.SilkS")
			(hide yes)
			(effects
				(font
					(size 1.27 1.27)
				)
			)
		)
		(property "Value" "RB551V30-GP"
			(at 0 -6.7818 180)
			(unlocked yes)
			(layer "F.Fab")
			(hide yes)
			(effects
				(font
					(size 1.016 1.016)
					(thickness 0.1524)
				)
			)
		)
		(property "Device Type" "SOD323AKH38"
			(at 0 -8.6868 180)
			(unlocked yes)
			(layer "F.Fab")
			(hide yes)
			(effects
				(font
					(size 1.016 1.016)
					(thickness 0.1524)
				)
			)
		)
		(duplicate_pad_numbers_are_jumpers no)
		(fp_line
			(start 0.889 2.159)
			(end -0.889 2.159)
			(stroke
				(width 0.1524)
				(type default)
			)
			(layer "F.SilkS")
		)
		(fp_line
			(start 0.889 -1.9304)
			(end 0.889 2.159)
			(stroke
				(width 0.1524)
				(type default)
			)
			(layer "F.SilkS")
		)
		(fp_line
			(start 0.762 2.0574)
			(end -0.762 2.0574)
			(stroke
				(width 0.508)
				(type default)
			)
			(layer "F.SilkS")
		)
		(fp_line
			(start -0.889 2.159)
			(end -0.889 -1.9304)
			(stroke
				(width 0.1524)
				(type default)
			)
			(layer "F.SilkS")
		)
		(fp_line
			(start -0.889 -1.9304)
			(end 0.889 -1.9304)
			(stroke
				(width 0.1524)
				(type default)
			)
			(layer "F.SilkS")
		)
		(fp_rect
			(start -1.016 2.3114)
			(end 1.016 -2.0066)
			(stroke
				(width 0)
				(type default)
			)
			(fill no)
			(layer "F.CrtYd")
		)
		(fp_poly
			(pts
				(xy -1.016 -2.0066) (xy 1.016 -2.0066) (xy 1.016 2.3114) (xy -1.016 2.3114)
			)
			(stroke
				(width 0)
				(type default)
			)
			(fill no)
			(layer "F.Fab")
		)
		(pad "A" smd rect
			(at 0 -1.143 180)
			(size 0.5588 1.016)
			(layers "F.Cu" "F.Mask" "F.Paste")
			(net "SW_HDD_R17")
		)
		(pad "K" smd rect
			(at 0 1.143 180)
			(size 0.5588 1.016)
			(layers "F.Cu" "F.Mask" "F.Paste")
			(net "SW_HDD_N17")
		)
	)
	(footprint ""
		(layer "F.Cu")
		(at 332.359 -36.83 180)
		(property "Reference" "C421"
			(at 0 0 180)
			(layer "F.SilkS")
			(hide yes)
			(effects
				(font
					(size 1.27 1.27)
				)
			)
		)
		(property "Value" "SC10U16V6KX-2GP"
			(at -0.0762 -5.1308 180)
			(unlocked yes)
			(layer "F.Fab")
			(hide yes)
			(effects
				(font
					(size 1.016 1.016)
					(thickness 0.1524)
				)
			)
		)
		(property "Device Type" "C1206H71"
			(at -0.127 -6.6548 180)
			(unlocked yes)
			(layer "F.Fab")
			(hide yes)
			(effects
				(font
					(size 1.016 1.016)
					(thickness 0.1524)
				)
			)
		)
		(duplicate_pad_numbers_are_jumpers no)
		(fp_line
			(start 1.016 2.2352)
			(end -1.016 2.2352)
			(stroke
				(width 0.1524)
				(type default)
			)
			(layer "F.SilkS")
		)
		(fp_line
			(start 1.016 0.8382)
			(end 1.016 2.2352)
			(stroke
				(width 0.1524)
				(type default)
			)
			(layer "F.SilkS")
		)
		(fp_line
			(start 1.016 -2.2352)
			(end 1.016 -0.8382)
			(stroke
				(width 0.1524)
				(type default)
			)
			(layer "F.SilkS")
		)
		(fp_line
			(start -1.016 2.2352)
			(end -1.016 0.8382)
			(stroke
				(width 0.1524)
				(type default)
			)
			(layer "F.SilkS")
		)
		(fp_line
			(start -1.016 -0.8382)
			(end -1.016 -2.2352)
			(stroke
				(width 0.1524)
				(type default)
			)
			(layer "F.SilkS")
		)
		(fp_line
			(start -1.016 -2.2352)
			(end 1.016 -2.2352)
			(stroke
				(width 0.1524)
				(type default)
			)
			(layer "F.SilkS")
		)
		(fp_rect
			(start -1.0922 2.3114)
			(end 1.0922 -2.3114)
			(stroke
				(width 0)
				(type default)
			)
			(fill no)
			(layer "F.CrtYd")
		)
		(fp_poly
			(pts
				(xy 1.0922 -2.3114) (xy 1.0922 2.3114) (xy -1.0922 2.3114) (xy -1.0922 -2.3114)
			)
			(stroke
				(width 0)
				(type default)
			)
			(fill no)
			(layer "F.Fab")
		)
		(pad "1" smd rect
			(at 0 -1.397 180)
			(size 1.651 1.27)
			(layers "F.Cu" "F.Mask" "F.Paste")
			(net "P5V_HDD30")
		)
		(pad "2" smd rect
			(at 0 1.397 180)
			(size 1.651 1.27)
			(layers "F.Cu" "F.Mask" "F.Paste")
			(net "GND")
		)
	)
	(footprint ""
		(layer "F.Cu")
		(at 52.29606 -120.444006 -90)
		(property "Reference" "R1117"
			(at 0 0 270)
			(layer "F.SilkS")
			(hide yes)
			(effects
				(font
					(size 1.27 1.27)
				)
			)
		)
		(property "Value" "0R2J-2-GP"
			(at 0.064008 -3.993896 270)
			(unlocked yes)
			(layer "F.Fab")
			(hide yes)
			(effects
				(font
					(size 1.016 1.016)
					(thickness 0.1524)
				)
			)
		)
		(property "Device Type" "R402H16"
			(at 0.064008 -5.517896 270)
			(unlocked yes)
			(layer "F.Fab")
			(hide yes)
			(effects
				(font
					(size 1.016 1.016)
					(thickness 0.1524)
				)
			)
		)
		(duplicate_pad_numbers_are_jumpers no)
		(fp_line
			(start -0.508 -0.9398)
			(end -0.508 0.9398)
			(stroke
				(width 0.1524)
				(type default)
			)
			(layer "F.SilkS")
		)
		(fp_line
			(start 0.508 -0.9398)
			(end -0.508 -0.9398)
			(stroke
				(width 0.1524)
				(type default)
			)
			(layer "F.SilkS")
		)
		(fp_rect
			(start -0.508 0.9398)
			(end 0.508 -0.9398)
			(stroke
				(width 0)
				(type default)
			)
			(fill no)
			(layer "F.CrtYd")
		)
		(fp_rect
			(start -0.508 0.9398)
			(end 0.508 -0.9398)
			(stroke
				(width 0)
				(type default)
			)
			(fill no)
			(layer "F.Fab")
		)
		(pad "1" smd custom
			(at 0 -0.4445 270)
			(size 0.1397 0.1397)
			(layers "F.Cu" "F.Mask" "F.Paste")
			(net "P12V_B_PGOOD")
			(options
				(clearance outline)
				(anchor circle)
			)
			(primitives
				(gr_poly
					(pts
						(arc
							(start -0.1778 -0.2794)
							(mid -0.249642 -0.249642)
							(end -0.2794 -0.1778)
						)
						(arc
							(start -0.2794 0.1778)
							(mid -0.249642 0.249642)
							(end -0.1778 0.2794)
						)
						(arc
							(start 0.1778 0.2794)
							(mid 0.249642 0.249642)
							(end 0.2794 0.1778)
						)
						(arc
							(start 0.2794 -0.1778)
							(mid 0.249642 -0.249642)
							(end 0.1778 -0.2794)
						)
					)
					(width 0)
					(fill yes)
				)
			)
		)
		(pad "2" smd custom
			(at 0 0.4445 270)
			(size 0.1397 0.1397)
			(layers "F.Cu" "F.Mask" "F.Paste")
			(net "P5V_B_2_EN_R")
			(options
				(clearance outline)
				(anchor circle)
			)
			(primitives
				(gr_poly
					(pts
						(arc
							(start -0.1778 -0.2794)
							(mid -0.249642 -0.249642)
							(end -0.2794 -0.1778)
						)
						(arc
							(start -0.2794 0.1778)
							(mid -0.249642 0.249642)
							(end -0.1778 0.2794)
						)
						(arc
							(start 0.1778 0.2794)
							(mid 0.249642 0.249642)
							(end 0.2794 0.1778)
						)
						(arc
							(start 0.2794 -0.1778)
							(mid 0.249642 -0.249642)
							(end 0.1778 -0.2794)
						)
					)
					(width 0)
					(fill yes)
				)
			)
		)
	)
	(footprint ""
		(layer "F.Cu")
		(at 35.687 -266.065 90)
		(property "Reference" "R902"
			(at 0 0 90)
			(layer "F.SilkS")
			(hide yes)
			(effects
				(font
					(size 1.27 1.27)
				)
			)
		)
		(property "Value" "220R3F-1-GP"
			(at -0.0254 -2.5146 90)
			(unlocked yes)
			(layer "F.Fab")
			(hide yes)
			(effects
				(font
					(size 1.016 1.016)
					(thickness 0.1524)
				)
			)
		)
		(property "Device Type" "R603H22"
			(at -0.0254 -4.0386 90)
			(unlocked yes)
			(layer "F.Fab")
			(hide yes)
			(effects
				(font
					(size 1.016 1.016)
					(thickness 0.1524)
				)
			)
		)
		(duplicate_pad_numbers_are_jumpers no)
		(fp_line
			(start 0.2032 0)
			(end 0.4826 0)
			(stroke
				(width 0.2032)
				(type default)
			)
			(layer "F.SilkS")
		)
		(fp_line
			(start -0.4826 0)
			(end -0.2032 0)
			(stroke
				(width 0.2032)
				(type default)
			)
			(layer "F.SilkS")
		)
		(fp_rect
			(start -0.5842 1.3335)
			(end 0.5842 -1.3335)
			(stroke
				(width 0)
				(type default)
			)
			(fill no)
			(layer "F.CrtYd")
		)
		(fp_rect
			(start -0.5842 1.3335)
			(end 0.5842 -1.3335)
			(stroke
				(width 0)
				(type default)
			)
			(fill no)
			(layer "F.Fab")
		)
		(pad "1" smd custom
			(at 0 -0.762 90)
			(size 0.2159 0.2159)
			(layers "F.Cu" "F.Mask" "F.Paste")
			(net "HDD_PRSNT_0")
			(options
				(clearance outline)
				(anchor circle)
			)
			(primitives
				(gr_poly
					(pts
						(arc
							(start -0.3302 -0.4318)
							(mid -0.402042 -0.402042)
							(end -0.4318 -0.3302)
						)
						(arc
							(start -0.4318 0.3302)
							(mid -0.402042 0.402042)
							(end -0.3302 0.4318)
						)
						(arc
							(start 0.3302 0.4318)
							(mid 0.402042 0.402042)
							(end 0.4318 0.3302)
						)
						(arc
							(start 0.4318 -0.3302)
							(mid 0.402042 -0.402042)
							(end 0.3302 -0.4318)
						)
					)
					(width 0)
					(fill yes)
				)
			)
		)
		(pad "2" smd custom
			(at 0 0.762 90)
			(size 0.2159 0.2159)
			(layers "F.Cu" "F.Mask" "F.Paste")
			(net "DRIVE_B_0_INS")
			(options
				(clearance outline)
				(anchor circle)
			)
			(primitives
				(gr_poly
					(pts
						(arc
							(start -0.3302 -0.4318)
							(mid -0.402042 -0.402042)
							(end -0.4318 -0.3302)
						)
						(arc
							(start -0.4318 0.3302)
							(mid -0.402042 0.402042)
							(end -0.3302 0.4318)
						)
						(arc
							(start 0.3302 0.4318)
							(mid 0.402042 0.402042)
							(end 0.4318 0.3302)
						)
						(arc
							(start 0.4318 -0.3302)
							(mid 0.402042 -0.402042)
							(end 0.3302 -0.4318)
						)
					)
					(width 0)
					(fill yes)
				)
			)
		)
	)
	(footprint ""
		(layer "F.Cu")
		(at 442.686186 -121.845578)
		(property "Reference" "R1154"
			(at 0 0 0)
			(layer "F.SilkS")
			(hide yes)
			(effects
				(font
					(size 1.27 1.27)
				)
			)
		)
		(property "Value" "49K9R2F-L-GP"
			(at 0.064008 -3.993896 0)
			(unlocked yes)
			(layer "F.Fab")
			(hide yes)
			(effects
				(font
					(size 1.016 1.016)
					(thickness 0.1524)
				)
			)
		)
		(property "Device Type" "R402H16"
			(at 0.064008 -5.517896 0)
			(unlocked yes)
			(layer "F.Fab")
			(hide yes)
			(effects
				(font
					(size 1.016 1.016)
					(thickness 0.1524)
				)
			)
		)
		(duplicate_pad_numbers_are_jumpers no)
		(fp_line
			(start -0.508 -0.9398)
			(end -0.508 0.9398)
			(stroke
				(width 0.1524)
				(type default)
			)
			(layer "F.SilkS")
		)
		(fp_line
			(start 0.508 -0.9398)
			(end -0.508 -0.9398)
			(stroke
				(width 0.1524)
				(type default)
			)
			(layer "F.SilkS")
		)
		(fp_rect
			(start -0.508 0.9398)
			(end 0.508 -0.9398)
			(stroke
				(width 0)
				(type default)
			)
			(fill no)
			(layer "F.CrtYd")
		)
		(fp_rect
			(start -0.508 0.9398)
			(end 0.508 -0.9398)
			(stroke
				(width 0)
				(type default)
			)
			(fill no)
			(layer "F.Fab")
		)
		(pad "1" smd custom
			(at 0 -0.4445)
			(size 0.1397 0.1397)
			(layers "F.Cu" "F.Mask" "F.Paste")
			(net "P12V_B")
			(options
				(clearance outline)
				(anchor circle)
			)
			(primitives
				(gr_poly
					(pts
						(arc
							(start -0.1778 -0.2794)
							(mid -0.249642 -0.249642)
							(end -0.2794 -0.1778)
						)
						(arc
							(start -0.2794 0.1778)
							(mid -0.249642 0.249642)
							(end -0.1778 0.2794)
						)
						(arc
							(start 0.1778 0.2794)
							(mid 0.249642 0.249642)
							(end 0.2794 0.1778)
						)
						(arc
							(start 0.2794 -0.1778)
							(mid 0.249642 -0.249642)
							(end 0.1778 -0.2794)
						)
					)
					(width 0)
					(fill yes)
				)
			)
		)
		(pad "2" smd custom
			(at 0 0.4445)
			(size 0.1397 0.1397)
			(layers "F.Cu" "F.Mask" "F.Paste")
			(net "P5V_B_4_EN_R")
			(options
				(clearance outline)
				(anchor circle)
			)
			(primitives
				(gr_poly
					(pts
						(arc
							(start -0.1778 -0.2794)
							(mid -0.249642 -0.249642)
							(end -0.2794 -0.1778)
						)
						(arc
							(start -0.2794 0.1778)
							(mid -0.249642 0.249642)
							(end -0.1778 0.2794)
						)
						(arc
							(start 0.1778 0.2794)
							(mid 0.249642 0.249642)
							(end 0.2794 0.1778)
						)
						(arc
							(start 0.2794 -0.1778)
							(mid 0.249642 -0.249642)
							(end 0.1778 -0.2794)
						)
					)
					(width 0)
					(fill yes)
				)
			)
		)
	)
	(footprint ""
		(layer "F.Cu")
		(at 432.213004 -357.2256)
		(property "Reference" "D48"
			(at 0 0 0)
			(layer "F.SilkS")
			(hide yes)
			(effects
				(font
					(size 1.27 1.27)
				)
			)
		)
		(property "Value" "RB551V30-GP"
			(at 0 -6.7818 0)
			(unlocked yes)
			(layer "F.Fab")
			(hide yes)
			(effects
				(font
					(size 1.016 1.016)
					(thickness 0.1524)
				)
			)
		)
		(property "Device Type" "SOD323AKH38"
			(at 0 -8.6868 0)
			(unlocked yes)
			(layer "F.Fab")
			(hide yes)
			(effects
				(font
					(size 1.016 1.016)
					(thickness 0.1524)
				)
			)
		)
		(duplicate_pad_numbers_are_jumpers no)
		(fp_line
			(start -0.889 -1.9304)
			(end 0.889 -1.9304)
			(stroke
				(width 0.1524)
				(type default)
			)
			(layer "F.SilkS")
		)
		(fp_line
			(start -0.889 2.159)
			(end -0.889 -1.9304)
			(stroke
				(width 0.1524)
				(type default)
			)
			(layer "F.SilkS")
		)
		(fp_line
			(start 0.762 2.0574)
			(end -0.762 2.0574)
			(stroke
				(width 0.508)
				(type default)
			)
			(layer "F.SilkS")
		)
		(fp_line
			(start 0.889 -1.9304)
			(end 0.889 2.159)
			(stroke
				(width 0.1524)
				(type default)
			)
			(layer "F.SilkS")
		)
		(fp_line
			(start 0.889 2.159)
			(end -0.889 2.159)
			(stroke
				(width 0.1524)
				(type default)
			)
			(layer "F.SilkS")
		)
		(fp_rect
			(start -1.016 2.3114)
			(end 1.016 -2.0066)
			(stroke
				(width 0)
				(type default)
			)
			(fill no)
			(layer "F.CrtYd")
		)
		(fp_poly
			(pts
				(xy -1.016 -2.0066) (xy 1.016 -2.0066) (xy 1.016 2.3114) (xy -1.016 2.3114)
			)
			(stroke
				(width 0)
				(type default)
			)
			(fill no)
			(layer "F.Fab")
		)
		(pad "A" smd rect
			(at 0 -1.143)
			(size 0.5588 1.016)
			(layers "F.Cu" "F.Mask" "F.Paste")
			(net "GATE_FAN3")
		)
		(pad "K" smd rect
			(at 0 1.143)
			(size 0.5588 1.016)
			(layers "F.Cu" "F.Mask" "F.Paste")
			(net "GATE_FAN3_R")
		)
	)
)
